# S9S_MB_2U (Grand Teton) — schematic netlist excerpt (pin names and nets, part order shuffled) for the footprints in the layout excerpt that follows; sources: Cadence DE-HDL packaged netlist, KiCad conversion of 03242023_DA0F0TMBIJ0_F0T_Motherboard_J_brd_V01_OCP.brd

R1839  Q_RES  0 5% EMPTY  pkg 0402LF  page 185 : A = RST_PFR_OVR_RTC ; B = RST_RTCRST_N
R2578  Q_RES  150 1% CHIP  pkg 0402LF  page 296 : A = SVID_CLK1_CPU1_R ; B = SVID_CLK_PVCCD_HV_CPU1_R

(kicad_pcb
	(version 20260206)
	(generator "pcbnew")
	(generator_version "10.0")
	(general
		(thickness 1.6)
		(legacy_teardrops no)
	)
	(paper "A4")
	(title_block
		(title "03242023_DA0F0TMBIJ0_F0T_Motherboard_J_brd_V01_OCP.brd")
		(comment 1 "Grand Teton / footprints 2390-2391 of 6105")
	)
	(layers
		(0 "F.Cu" signal "TOP")
		(4 "In1.Cu" signal "GND")
		(6 "In2.Cu" signal "IN1")
		(8 "In3.Cu" signal "GND1")
		(10 "In4.Cu" signal "IN2")
		(12 "In5.Cu" signal "GND2")
		(14 "In6.Cu" signal "IN3")
		(16 "In7.Cu" signal "GND3")
		(18 "In8.Cu" signal "VCC")
		(20 "In9.Cu" signal "VCC1")
		(22 "In10.Cu" signal "GND4")
		(24 "In11.Cu" signal "IN4")
		(26 "In12.Cu" signal "GND5")
		(28 "In13.Cu" signal "IN5")
		(30 "In14.Cu" signal "GND6")
		(32 "In15.Cu" signal "IN6")
		(34 "In16.Cu" signal "GND7")
		(2 "B.Cu" signal "BOTTOM")
		(9 "F.Adhes" user "F.Adhesive")
		(11 "B.Adhes" user "B.Adhesive")
		(13 "F.Paste" user "Package Geometry/Pastemask Top")
		(15 "B.Paste" user "Package Geometry/Pastemask Bottom")
		(5 "F.SilkS" user "Ref Des/Silkscreen Top")
		(7 "B.SilkS" user "Ref Des/Silkscreen Bottom")
		(1 "F.Mask" user "Board Geometry/Soldermask Top")
		(3 "B.Mask" user "Board Geometry/Soldermask Bottom")
		(17 "Dwgs.User" user "User.Drawings")
		(19 "Cmts.User" user "User.Comments")
		(21 "Eco1.User" user "User.Eco1")
		(23 "Eco2.User" user "User.Eco2")
		(25 "Edge.Cuts" user "Board Geometry/Outline")
		(27 "Margin" user)
		(31 "F.CrtYd" user "Package Geometry/Place Bound Top")
		(29 "B.CrtYd" user "Package Geometry/Place Bound Bottom")
		(35 "F.Fab" user "Ref Des/Assembly Top")
		(33 "B.Fab" user "Ref Des/Assembly Bottom")
	)
	(footprint ""
		(layer "F.Cu")
		(at 203.326492 -101.606604 -90)
		(property "Reference" "R1839"
			(at 0 0 270)
			(layer "F.SilkS")
			(hide yes)
			(effects
				(font
					(size 1.27 1.27)
				)
			)
		)
		(property "Value" ""
			(at 0 0 270)
			(layer "F.Fab")
			(effects
				(font
					(size 1.27 1.27)
				)
			)
		)
		(duplicate_pad_numbers_are_jumpers no)
		(fp_line
			(start -0.7874 0.4064)
			(end -0.7874 -0.4064)
			(stroke
				(width 0.1524)
				(type default)
			)
			(layer "F.SilkS")
		)
		(fp_line
			(start 0.7874 0.4064)
			(end -0.7874 0.4064)
			(stroke
				(width 0.1524)
				(type default)
			)
			(layer "F.SilkS")
		)
		(fp_line
			(start -0.7874 -0.4064)
			(end 0.7874 -0.4064)
			(stroke
				(width 0.1524)
				(type default)
			)
			(layer "F.SilkS")
		)
		(fp_line
			(start 0.7874 -0.4064)
			(end 0.7874 0.4064)
			(stroke
				(width 0.1524)
				(type default)
			)
			(layer "F.SilkS")
		)
		(fp_line
			(start -0.67945 0.3048)
			(end -0.67945 -0.305054)
			(stroke
				(width 0.1)
				(type default)
			)
			(layer "F.Fab")
		)
		(fp_line
			(start -0.12065 0.3048)
			(end -0.67945 0.3048)
			(stroke
				(width 0.1)
				(type default)
			)
			(layer "F.Fab")
		)
		(fp_line
			(start 0.120396 0.3048)
			(end 0.120396 0.2794)
			(stroke
				(width 0.1)
				(type default)
			)
			(layer "F.Fab")
		)
		(fp_line
			(start 0.67945 0.3048)
			(end 0.120396 0.3048)
			(stroke
				(width 0.1)
				(type default)
			)
			(layer "F.Fab")
		)
		(fp_line
			(start -0.12065 0.2794)
			(end -0.12065 0.3048)
			(stroke
				(width 0.1)
				(type default)
			)
			(layer "F.Fab")
		)
		(fp_line
			(start 0.120396 0.2794)
			(end -0.12065 0.2794)
			(stroke
				(width 0.1)
				(type default)
			)
			(layer "F.Fab")
		)
		(fp_line
			(start -0.12065 -0.2794)
			(end 0.12065 -0.2794)
			(stroke
				(width 0.1)
				(type default)
			)
			(layer "F.Fab")
		)
		(fp_line
			(start 0.12065 -0.2794)
			(end 0.12065 -0.3048)
			(stroke
				(width 0.1)
				(type default)
			)
			(layer "F.Fab")
		)
		(fp_line
			(start 0.12065 -0.3048)
			(end 0.67945 -0.3048)
			(stroke
				(width 0.1)
				(type default)
			)
			(layer "F.Fab")
		)
		(fp_line
			(start 0.67945 -0.3048)
			(end 0.67945 0.3048)
			(stroke
				(width 0.1)
				(type default)
			)
			(layer "F.Fab")
		)
		(fp_line
			(start -0.67945 -0.305054)
			(end -0.12065 -0.305054)
			(stroke
				(width 0.1)
				(type default)
			)
			(layer "F.Fab")
		)
		(fp_line
			(start -0.12065 -0.305054)
			(end -0.12065 -0.2794)
			(stroke
				(width 0.1)
				(type default)
			)
			(layer "F.Fab")
		)
		(pad "1" smd circle
			(at -0.40005 0 270)
			(size 0 0)
			(layers "F.Cu" "F.Mask" "F.Paste")
			(net "RST_PFR_OVR_RTC")
		)
		(pad "2" smd circle
			(at 0.40005 0 270)
			(size 0 0)
			(layers "F.Cu" "F.Mask" "F.Paste")
			(net "RST_RTCRST_N")
		)
	)
	(footprint ""
		(layer "F.Cu")
		(at 22.13356 -165.751256)
		(property "Reference" "R2578"
			(at 0 0 0)
			(layer "F.SilkS")
			(hide yes)
			(effects
				(font
					(size 1.27 1.27)
				)
			)
		)
		(property "Value" ""
			(at 0 0 0)
			(layer "F.Fab")
			(effects
				(font
					(size 1.27 1.27)
				)
			)
		)
		(duplicate_pad_numbers_are_jumpers no)
		(fp_line
			(start -0.7874 -0.4064)
			(end 0.7874 -0.4064)
			(stroke
				(width 0.1524)
				(type default)
			)
			(layer "F.SilkS")
		)
		(fp_line
			(start -0.7874 0.4064)
			(end -0.7874 -0.4064)
			(stroke
				(width 0.1524)
				(type default)
			)
			(layer "F.SilkS")
		)
		(fp_line
			(start 0.7874 -0.4064)
			(end 0.7874 0.4064)
			(stroke
				(width 0.1524)
				(type default)
			)
			(layer "F.SilkS")
		)
		(fp_line
			(start 0.7874 0.4064)
			(end -0.7874 0.4064)
			(stroke
				(width 0.1524)
				(type default)
			)
			(layer "F.SilkS")
		)
		(fp_line
			(start -0.67945 -0.305054)
			(end -0.12065 -0.305054)
			(stroke
				(width 0.1)
				(type default)
			)
			(layer "F.Fab")
		)
		(fp_line
			(start -0.67945 0.3048)
			(end -0.67945 -0.305054)
			(stroke
				(width 0.1)
				(type default)
			)
			(layer "F.Fab")
		)
		(fp_line
			(start -0.12065 -0.305054)
			(end -0.12065 -0.2794)
			(stroke
				(width 0.1)
				(type default)
			)
			(layer "F.Fab")
		)
		(fp_line
			(start -0.12065 -0.2794)
			(end 0.12065 -0.2794)
			(stroke
				(width 0.1)
				(type default)
			)
			(layer "F.Fab")
		)
		(fp_line
			(start -0.12065 0.2794)
			(end -0.12065 0.3048)
			(stroke
				(width 0.1)
				(type default)
			)
			(layer "F.Fab")
		)
		(fp_line
			(start -0.12065 0.3048)
			(end -0.67945 0.3048)
			(stroke
				(width 0.1)
				(type default)
			)
			(layer "F.Fab")
		)
		(fp_line
			(start 0.120396 0.2794)
			(end -0.12065 0.2794)
			(stroke
				(width 0.1)
				(type default)
			)
			(layer "F.Fab")
		)
		(fp_line
			(start 0.120396 0.3048)
			(end 0.120396 0.2794)
			(stroke
				(width 0.1)
				(type default)
			)
			(layer "F.Fab")
		)
		(fp_line
			(start 0.12065 -0.3048)
			(end 0.67945 -0.3048)
			(stroke
				(width 0.1)
				(type default)
			)
			(layer "F.Fab")
		)
		(fp_line
			(start 0.12065 -0.2794)
			(end 0.12065 -0.3048)
			(stroke
				(width 0.1)
				(type default)
			)
			(layer "F.Fab")
		)
		(fp_line
			(start 0.67945 -0.3048)
			(end 0.67945 0.3048)
			(stroke
				(width 0.1)
				(type default)
			)
			(layer "F.Fab")
		)
		(fp_line
			(start 0.67945 0.3048)
			(end 0.120396 0.3048)
			(stroke
				(width 0.1)
				(type default)
			)
			(layer "F.Fab")
		)
		(pad "1" smd circle
			(at -0.40005 0)
			(size 0 0)
			(layers "F.Cu" "F.Mask" "F.Paste")
			(net "SVID_CLK1_CPU1_R")
		)
		(pad "2" smd circle
			(at 0.40005 0)
			(size 0 0)
			(layers "F.Cu" "F.Mask" "F.Paste")
			(net "SVID_CLK_PVCCD_HV_CPU1_R")
		)
	)
)
